(kicad_pcb
	(version 20260206)
	(generator "pcbnew")
	(generator_version "10.0")
	(general
		(thickness 1.6)
		(legacy_teardrops no)
	)
	(paper "A4")
	(title_block
		(title "01162023_DA0F0TEBIF0_F0T_Expander_BD_F_brd_V02_OCP.brd")
		(comment 1 "Grand Teton / footprints 5741-5746 of 9728")
	)
	(layers
		(0 "F.Cu" signal "TOP")
		(4 "In1.Cu" signal "GND")
		(6 "In2.Cu" signal "VCC")
		(8 "In3.Cu" signal "VCC1")
		(10 "In4.Cu" signal "GND1")
		(12 "In5.Cu" signal "IN1")
		(14 "In6.Cu" signal "GND2")
		(16 "In7.Cu" signal "IN2")
		(18 "In8.Cu" signal "GND3")
		(20 "In9.Cu" signal "IN3")
		(22 "In10.Cu" signal "GND4")
		(24 "In11.Cu" signal "IN4")
		(26 "In12.Cu" signal "GND5")
		(28 "In13.Cu" signal "IN5")
		(30 "In14.Cu" signal "GND6")
		(32 "In15.Cu" signal "IN6")
		(34 "In16.Cu" signal "GND7")
		(2 "B.Cu" signal "BOTTOM")
		(9 "F.Adhes" user "F.Adhesive")
		(11 "B.Adhes" user "B.Adhesive")
		(13 "F.Paste" user "Package Geometry/Pastemask Top")
		(15 "B.Paste" user "Package Geometry/Pastemask Bottom")
		(5 "F.SilkS" user "Ref Des/Silkscreen Top")
		(7 "B.SilkS" user "Ref Des/Silkscreen Bottom")
		(1 "F.Mask" user "Board Geometry/Soldermask Top")
		(3 "B.Mask" user "Board Geometry/Soldermask Bottom")
		(17 "Dwgs.User" user "User.Drawings")
		(19 "Cmts.User" user "User.Comments")
		(21 "Eco1.User" user "User.Eco1")
		(23 "Eco2.User" user "User.Eco2")
		(25 "Edge.Cuts" user "Board Geometry/Outline")
		(27 "Margin" user)
		(31 "F.CrtYd" user "Package Geometry/Place Bound Top")
		(29 "B.CrtYd" user "Package Geometry/Place Bound Bottom")
		(35 "F.Fab" user "Ref Des/Assembly Top")
		(33 "B.Fab" user "Ref Des/Assembly Bottom")
	)
	(footprint ""
		(layer "F.Cu")
		(at 193.939668 -406.358598 90)
		(property "Reference" "U340"
			(at -4.146296 0.955548 0)
			(unlocked yes)
			(layer "F.SilkS")
			(effects
				(font
					(size 0.7874 0.5842)
					(thickness 0.1524)
				)
				(justify left)
			)
		)
		(property "Value" ""
			(at 0 0 90)
			(layer "F.Fab")
			(effects
				(font
					(size 1.27 1.27)
				)
			)
		)
		(duplicate_pad_numbers_are_jumpers no)
		(fp_line
			(start 2.0574 -1.651)
			(end 2.0574 1.651)
			(stroke
				(width 0.1524)
				(type default)
			)
			(layer "F.SilkS")
		)
		(fp_line
			(start 0.381 -1.651)
			(end 2.0574 -1.651)
			(stroke
				(width 0.1524)
				(type default)
			)
			(layer "F.SilkS")
		)
		(fp_line
			(start -0.381 -1.651)
			(end 0 -1.016)
			(stroke
				(width 0.1524)
				(type default)
			)
			(layer "F.SilkS")
		)
		(fp_line
			(start -2.0574 -1.651)
			(end -0.381 -1.651)
			(stroke
				(width 0.1524)
				(type default)
			)
			(layer "F.SilkS")
		)
		(fp_line
			(start 0 -1.016)
			(end 0.381 -1.651)
			(stroke
				(width 0.1524)
				(type default)
			)
			(layer "F.SilkS")
		)
		(fp_line
			(start 2.0574 1.651)
			(end -2.0574 1.651)
			(stroke
				(width 0.1524)
				(type default)
			)
			(layer "F.SilkS")
		)
		(fp_line
			(start -2.0574 1.651)
			(end -2.0574 -1.651)
			(stroke
				(width 0.1524)
				(type default)
			)
			(layer "F.SilkS")
		)
		(fp_poly
			(pts
				(xy -2.793492 -1.531112) (xy -2.351532 -1.973072) (xy -2.19202 -1.349502)
			)
			(stroke
				(width 0)
				(type default)
			)
			(fill yes)
			(layer "F.SilkS")
		)
		(fp_line
			(start 0.899922 -1.549908)
			(end 0.899922 -1.199896)
			(stroke
				(width 0.1)
				(type default)
			)
			(layer "F.Fab")
		)
		(fp_line
			(start -0.899922 -1.549908)
			(end 0.899922 -1.549908)
			(stroke
				(width 0.1)
				(type default)
			)
			(layer "F.Fab")
		)
		(fp_line
			(start 1.599946 -1.199896)
			(end 1.599946 1.199896)
			(stroke
				(width 0.1)
				(type default)
			)
			(layer "F.Fab")
		)
		(fp_line
			(start 0.899922 -1.199896)
			(end 1.599946 -1.199896)
			(stroke
				(width 0.1)
				(type default)
			)
			(layer "F.Fab")
		)
		(fp_line
			(start -0.899922 -1.199896)
			(end -0.899922 -1.549908)
			(stroke
				(width 0.1)
				(type default)
			)
			(layer "F.Fab")
		)
		(fp_line
			(start -1.599946 -1.199896)
			(end -0.899922 -1.199896)
			(stroke
				(width 0.1)
				(type default)
			)
			(layer "F.Fab")
		)
		(fp_line
			(start 1.599946 1.199896)
			(end 0.899922 1.199896)
			(stroke
				(width 0.1)
				(type default)
			)
			(layer "F.Fab")
		)
		(fp_line
			(start 0.899922 1.199896)
			(end 0.899922 1.549908)
			(stroke
				(width 0.1)
				(type default)
			)
			(layer "F.Fab")
		)
		(fp_line
			(start -0.899922 1.199896)
			(end -1.599946 1.199896)
			(stroke
				(width 0.1)
				(type default)
			)
			(layer "F.Fab")
		)
		(fp_line
			(start -1.599946 1.199896)
			(end -1.599946 -1.199896)
			(stroke
				(width 0.1)
				(type default)
			)
			(layer "F.Fab")
		)
		(fp_line
			(start 0.899922 1.549908)
			(end -0.899922 1.549908)
			(stroke
				(width 0.1)
				(type default)
			)
			(layer "F.Fab")
		)
		(fp_line
			(start -0.899922 1.549908)
			(end -0.899922 1.199896)
			(stroke
				(width 0.1)
				(type default)
			)
			(layer "F.Fab")
		)
		(fp_poly
			(pts
				(xy -2.71272 -0.719328) (xy -2.71272 -1.344168) (xy -2.159 -1.016)
			)
			(stroke
				(width 0)
				(type default)
			)
			(fill yes)
			(layer "F.Fab")
		)
		(pad "1" smd rect
			(at -1.225042 -0.94996)
			(size 0.5588 1.3462)
			(layers "F.Cu" "F.Mask" "F.Paste")
			(net "FM_HSC_FAULT_N")
		)
		(pad "2" smd rect
			(at -1.225042 0)
			(size 0.5588 1.3462)
			(layers "F.Cu" "F.Mask" "F.Paste")
			(net "HSC_ALERT1_R_N")
		)
		(pad "3" smd rect
			(at -1.225042 0.94996)
			(size 0.5588 1.3462)
			(layers "F.Cu" "F.Mask" "F.Paste")
			(net "GND")
		)
		(pad "4" smd rect
			(at 1.225042 0.94996)
			(size 0.5588 1.3462)
			(layers "F.Cu" "F.Mask" "F.Paste")
			(net "SMB_ALERT_HSC_N")
		)
		(pad "5" smd rect
			(at 1.225042 -0.94996)
			(size 0.5588 1.3462)
			(layers "F.Cu" "F.Mask" "F.Paste")
			(net "P3V3_AUX")
		)
	)
	(footprint ""
		(layer "F.Cu")
		(at 376.706384 -250.070874 -90)
		(property "Reference" "R1403"
			(at 0 0 270)
			(layer "F.SilkS")
			(hide yes)
			(effects
				(font
					(size 1.27 1.27)
				)
			)
		)
		(property "Value" ""
			(at 0 0 270)
			(layer "F.Fab")
			(effects
				(font
					(size 1.27 1.27)
				)
			)
		)
		(duplicate_pad_numbers_are_jumpers no)
		(fp_line
			(start -0.7874 0.4064)
			(end -0.7874 -0.4064)
			(stroke
				(width 0.1524)
				(type default)
			)
			(layer "F.SilkS")
		)
		(fp_line
			(start 0.7874 0.4064)
			(end -0.7874 0.4064)
			(stroke
				(width 0.1524)
				(type default)
			)
			(layer "F.SilkS")
		)
		(fp_line
			(start -0.7874 -0.4064)
			(end 0.7874 -0.4064)
			(stroke
				(width 0.1524)
				(type default)
			)
			(layer "F.SilkS")
		)
		(fp_line
			(start 0.7874 -0.4064)
			(end 0.7874 0.4064)
			(stroke
				(width 0.1524)
				(type default)
			)
			(layer "F.SilkS")
		)
		(fp_line
			(start -0.67945 0.3048)
			(end -0.67945 -0.305054)
			(stroke
				(width 0.1)
				(type default)
			)
			(layer "F.Fab")
		)
		(fp_line
			(start -0.12065 0.3048)
			(end -0.67945 0.3048)
			(stroke
				(width 0.1)
				(type default)
			)
			(layer "F.Fab")
		)
		(fp_line
			(start 0.120396 0.3048)
			(end 0.120396 0.2794)
			(stroke
				(width 0.1)
				(type default)
			)
			(layer "F.Fab")
		)
		(fp_line
			(start 0.67945 0.3048)
			(end 0.120396 0.3048)
			(stroke
				(width 0.1)
				(type default)
			)
			(layer "F.Fab")
		)
		(fp_line
			(start -0.12065 0.2794)
			(end -0.12065 0.3048)
			(stroke
				(width 0.1)
				(type default)
			)
			(layer "F.Fab")
		)
		(fp_line
			(start 0.120396 0.2794)
			(end -0.12065 0.2794)
			(stroke
				(width 0.1)
				(type default)
			)
			(layer "F.Fab")
		)
		(fp_line
			(start -0.12065 -0.2794)
			(end 0.12065 -0.2794)
			(stroke
				(width 0.1)
				(type default)
			)
			(layer "F.Fab")
		)
		(fp_line
			(start 0.12065 -0.2794)
			(end 0.12065 -0.3048)
			(stroke
				(width 0.1)
				(type default)
			)
			(layer "F.Fab")
		)
		(fp_line
			(start 0.12065 -0.3048)
			(end 0.67945 -0.3048)
			(stroke
				(width 0.1)
				(type default)
			)
			(layer "F.Fab")
		)
		(fp_line
			(start 0.67945 -0.3048)
			(end 0.67945 0.3048)
			(stroke
				(width 0.1)
				(type default)
			)
			(layer "F.Fab")
		)
		(fp_line
			(start -0.67945 -0.305054)
			(end -0.12065 -0.305054)
			(stroke
				(width 0.1)
				(type default)
			)
			(layer "F.Fab")
		)
		(fp_line
			(start -0.12065 -0.305054)
			(end -0.12065 -0.2794)
			(stroke
				(width 0.1)
				(type default)
			)
			(layer "F.Fab")
		)
		(pad "1" smd circle
			(at -0.40005 0 270)
			(size 0 0)
			(layers "F.Cu" "F.Mask" "F.Paste")
			(net "PEX3_DBG_MODE3")
		)
		(pad "2" smd circle
			(at 0.40005 0 270)
			(size 0 0)
			(layers "F.Cu" "F.Mask" "F.Paste")
			(net "P1V8_PEX")
		)
	)
	(footprint ""
		(layer "F.Cu")
		(at 52.610512 -18.61439 90)
		(property "Reference" "U127"
			(at -1.44399 2.407158 90)
			(unlocked yes)
			(layer "F.SilkS")
			(effects
				(font
					(size 0.7874 0.5842)
					(thickness 0.1524)
				)
				(justify left)
			)
		)
		(property "Value" ""
			(at 0 0 90)
			(layer "F.Fab")
			(effects
				(font
					(size 1.27 1.27)
				)
			)
		)
		(duplicate_pad_numbers_are_jumpers no)
		(fp_line
			(start 1.463548 -1.549908)
			(end 1.463548 1.549908)
			(stroke
				(width 0.1524)
				(type default)
			)
			(layer "F.SilkS")
		)
		(fp_line
			(start 0.762 -1.549908)
			(end 1.463548 -1.549908)
			(stroke
				(width 0.1524)
				(type default)
			)
			(layer "F.SilkS")
		)
		(fp_line
			(start -0.787908 -1.549908)
			(end 0 -0.762)
			(stroke
				(width 0.1524)
				(type default)
			)
			(layer "F.SilkS")
		)
		(fp_line
			(start -1.463548 -1.549908)
			(end -0.787908 -1.549908)
			(stroke
				(width 0.1524)
				(type default)
			)
			(layer "F.SilkS")
		)
		(fp_line
			(start 0 -0.762)
			(end 0.762 -1.549908)
			(stroke
				(width 0.1524)
				(type default)
			)
			(layer "F.SilkS")
		)
		(fp_line
			(start 1.463548 1.549908)
			(end -1.463548 1.549908)
			(stroke
				(width 0.1524)
				(type default)
			)
			(layer "F.SilkS")
		)
		(fp_line
			(start -1.463548 1.549908)
			(end -1.463548 -1.549908)
			(stroke
				(width 0.1524)
				(type default)
			)
			(layer "F.SilkS")
		)
		(fp_poly
			(pts
				(xy -3.4798 -1.359916) (xy -2.86004 -1.050036) (xy -3.4798 -0.740156)
			)
			(stroke
				(width 0)
				(type default)
			)
			(fill yes)
			(layer "F.SilkS")
		)
		(fp_line
			(start 1.549908 -1.549908)
			(end 1.549908 1.549908)
			(stroke
				(width 0.1)
				(type default)
			)
			(layer "F.Fab")
		)
		(fp_line
			(start -1.549908 -1.549908)
			(end 1.549908 -1.549908)
			(stroke
				(width 0.1)
				(type default)
			)
			(layer "F.Fab")
		)
		(fp_line
			(start 1.549908 1.549908)
			(end -1.549908 1.549908)
			(stroke
				(width 0.1)
				(type default)
			)
			(layer "F.Fab")
		)
		(fp_line
			(start -1.549908 1.549908)
			(end -1.549908 -1.549908)
			(stroke
				(width 0.1)
				(type default)
			)
			(layer "F.Fab")
		)
		(fp_poly
			(pts
				(xy -3.4798 -1.359916) (xy -2.86004 -1.050036) (xy -3.4798 -0.740156)
			)
			(stroke
				(width 0)
				(type default)
			)
			(fill yes)
			(layer "F.Fab")
		)
		(pad "1" smd rect
			(at -2.175002 -1.050036 180)
			(size 0.6096 1.1684)
			(layers "F.Cu" "F.Mask" "F.Paste")
			(net "P3V3_SSD1")
		)
		(pad "2" smd rect
			(at -2.175002 -0.32512 180)
			(size 0.4318 1.1684)
			(layers "F.Cu" "F.Mask" "F.Paste")
			(net "SMB_ISO_SSD1_SCL")
		)
		(pad "3" smd rect
			(at -2.175002 0.32512 180)
			(size 0.4318 1.1684)
			(layers "F.Cu" "F.Mask" "F.Paste")
			(net "SMB_ISO_SSD1_SDA")
		)
		(pad "4" smd rect
			(at -2.175002 1.050036 180)
			(size 0.6096 1.1684)
			(layers "F.Cu" "F.Mask" "F.Paste")
			(net "GND")
		)
		(pad "5" smd rect
			(at 2.175002 1.050036 180)
			(size 0.6096 1.1684)
			(layers "F.Cu" "F.Mask" "F.Paste")
			(net "SMB_SSD1_ISO_EN")
		)
		(pad "6" smd rect
			(at 2.175002 0.32512 180)
			(size 0.4318 1.1684)
			(layers "F.Cu" "F.Mask" "F.Paste")
			(net "SMB_BIC_I2C9_MUX0_SSD1_R_SDA")
		)
		(pad "7" smd rect
			(at 2.175002 -0.32512 180)
			(size 0.4318 1.1684)
			(layers "F.Cu" "F.Mask" "F.Paste")
			(net "SMB_BIC_I2C9_MUX0_SSD1_R_SCL")
		)
		(pad "8" smd rect
			(at 2.175002 -1.050036 180)
			(size 0.6096 1.1684)
			(layers "F.Cu" "F.Mask" "F.Paste")
			(net "P3V3_AUX")
		)
	)
	(footprint ""
		(layer "F.Cu")
		(at 457.935838 -316.300358)
		(property "Reference" "PC266"
			(at 0 0 0)
			(layer "F.SilkS")
			(hide yes)
			(effects
				(font
					(size 1.27 1.27)
				)
			)
		)
		(property "Value" ""
			(at 0 0 0)
			(layer "F.Fab")
			(effects
				(font
					(size 1.27 1.27)
				)
			)
		)
		(duplicate_pad_numbers_are_jumpers no)
		(fp_line
			(start -1.524 -0.762)
			(end 1.524 -0.762)
			(stroke
				(width 0.1524)
				(type default)
			)
			(layer "F.SilkS")
		)
		(fp_line
			(start -1.524 0.762)
			(end -1.524 -0.762)
			(stroke
				(width 0.1524)
				(type default)
			)
			(layer "F.SilkS")
		)
		(fp_line
			(start 1.524 -0.762)
			(end 1.524 0.762)
			(stroke
				(width 0.1524)
				(type default)
			)
			(layer "F.SilkS")
		)
		(fp_line
			(start 1.524 0.762)
			(end -1.524 0.762)
			(stroke
				(width 0.1524)
				(type default)
			)
			(layer "F.SilkS")
		)
		(fp_line
			(start -1.1049 -0.724916)
			(end -1.1049 0.724916)
			(stroke
				(width 0.1)
				(type default)
			)
			(layer "F.Fab")
		)
		(fp_line
			(start -1.1049 0.724916)
			(end 1.1049 0.724916)
			(stroke
				(width 0.1)
				(type default)
			)
			(layer "F.Fab")
		)
		(fp_line
			(start 1.1049 -0.724916)
			(end -1.1049 -0.724916)
			(stroke
				(width 0.1)
				(type default)
			)
			(layer "F.Fab")
		)
		(fp_line
			(start 1.1049 0.724916)
			(end 1.1049 -0.724916)
			(stroke
				(width 0.1)
				(type default)
			)
			(layer "F.Fab")
		)
		(pad "1" smd rect
			(at -0.889 0 180)
			(size 1.016 1.27)
			(layers "F.Cu" "F.Mask" "F.Paste")
			(net "SW_P12V_P1V25_PEX3_FLT")
		)
		(pad "2" smd rect
			(at 0.889 0 180)
			(size 1.016 1.27)
			(layers "F.Cu" "F.Mask" "F.Paste")
			(net "GND")
		)
	)
	(footprint ""
		(layer "F.Cu")
		(at 98.12528 -42.849038 180)
		(property "Reference" "R546"
			(at 0 0 180)
			(layer "F.SilkS")
			(hide yes)
			(effects
				(font
					(size 1.27 1.27)
				)
			)
		)
		(property "Value" ""
			(at 0 0 180)
			(layer "F.Fab")
			(effects
				(font
					(size 1.27 1.27)
				)
			)
		)
		(duplicate_pad_numbers_are_jumpers no)
		(fp_line
			(start 0.7874 0.4064)
			(end -0.7874 0.4064)
			(stroke
				(width 0.1524)
				(type default)
			)
			(layer "F.SilkS")
		)
		(fp_line
			(start 0.7874 -0.4064)
			(end 0.7874 0.4064)
			(stroke
				(width 0.1524)
				(type default)
			)
			(layer "F.SilkS")
		)
		(fp_line
			(start -0.7874 0.4064)
			(end -0.7874 -0.4064)
			(stroke
				(width 0.1524)
				(type default)
			)
			(layer "F.SilkS")
		)
		(fp_line
			(start -0.7874 -0.4064)
			(end 0.7874 -0.4064)
			(stroke
				(width 0.1524)
				(type default)
			)
			(layer "F.SilkS")
		)
		(fp_line
			(start 0.67945 0.3048)
			(end 0.120396 0.3048)
			(stroke
				(width 0.1)
				(type default)
			)
			(layer "F.Fab")
		)
		(fp_line
			(start 0.67945 -0.3048)
			(end 0.67945 0.3048)
			(stroke
				(width 0.1)
				(type default)
			)
			(layer "F.Fab")
		)
		(fp_line
			(start 0.12065 -0.2794)
			(end 0.12065 -0.3048)
			(stroke
				(width 0.1)
				(type default)
			)
			(layer "F.Fab")
		)
		(fp_line
			(start 0.12065 -0.3048)
			(end 0.67945 -0.3048)
			(stroke
				(width 0.1)
				(type default)
			)
			(layer "F.Fab")
		)
		(fp_line
			(start 0.120396 0.3048)
			(end 0.120396 0.2794)
			(stroke
				(width 0.1)
				(type default)
			)
			(layer "F.Fab")
		)
		(fp_line
			(start 0.120396 0.2794)
			(end -0.12065 0.2794)
			(stroke
				(width 0.1)
				(type default)
			)
			(layer "F.Fab")
		)
		(fp_line
			(start -0.12065 0.3048)
			(end -0.67945 0.3048)
			(stroke
				(width 0.1)
				(type default)
			)
			(layer "F.Fab")
		)
		(fp_line
			(start -0.12065 0.2794)
			(end -0.12065 0.3048)
			(stroke
				(width 0.1)
				(type default)
			)
			(layer "F.Fab")
		)
		(fp_line
			(start -0.12065 -0.2794)
			(end 0.12065 -0.2794)
			(stroke
				(width 0.1)
				(type default)
			)
			(layer "F.Fab")
		)
		(fp_line
			(start -0.12065 -0.305054)
			(end -0.12065 -0.2794)
			(stroke
				(width 0.1)
				(type default)
			)
			(layer "F.Fab")
		)
		(fp_line
			(start -0.67945 0.3048)
			(end -0.67945 -0.305054)
			(stroke
				(width 0.1)
				(type default)
			)
			(layer "F.Fab")
		)
		(fp_line
			(start -0.67945 -0.305054)
			(end -0.12065 -0.305054)
			(stroke
				(width 0.1)
				(type default)
			)
			(layer "F.Fab")
		)
		(pad "1" smd circle
			(at -0.40005 0 180)
			(size 0 0)
			(layers "F.Cu" "F.Mask" "F.Paste")
			(net "P12V_SSD3_R")
		)
		(pad "2" smd circle
			(at 0.40005 0 180)
			(size 0 0)
			(layers "F.Cu" "F.Mask" "F.Paste")
			(net "P12V_SSD3_VIN_P")
		)
	)
	(footprint ""
		(layer "F.Cu")
		(at 19.02714 -174.247048 -90)
		(property "Reference" "R502"
			(at 0 0 270)
			(layer "F.SilkS")
			(hide yes)
			(effects
				(font
					(size 1.27 1.27)
				)
			)
		)
		(property "Value" ""
			(at 0 0 270)
			(layer "F.Fab")
			(effects
				(font
					(size 1.27 1.27)
				)
			)
		)
		(duplicate_pad_numbers_are_jumpers no)
		(fp_line
			(start -0.7874 0.4064)
			(end -0.7874 -0.4064)
			(stroke
				(width 0.1524)
				(type default)
			)
			(layer "F.SilkS")
		)
		(fp_line
			(start 0.7874 0.4064)
			(end -0.7874 0.4064)
			(stroke
				(width 0.1524)
				(type default)
			)
			(layer "F.SilkS")
		)
		(fp_line
			(start -0.7874 -0.4064)
			(end 0.7874 -0.4064)
			(stroke
				(width 0.1524)
				(type default)
			)
			(layer "F.SilkS")
		)
		(fp_line
			(start 0.7874 -0.4064)
			(end 0.7874 0.4064)
			(stroke
				(width 0.1524)
				(type default)
			)
			(layer "F.SilkS")
		)
		(fp_line
			(start -0.67945 0.3048)
			(end -0.67945 -0.305054)
			(stroke
				(width 0.1)
				(type default)
			)
			(layer "F.Fab")
		)
		(fp_line
			(start -0.12065 0.3048)
			(end -0.67945 0.3048)
			(stroke
				(width 0.1)
				(type default)
			)
			(layer "F.Fab")
		)
		(fp_line
			(start 0.120396 0.3048)
			(end 0.120396 0.2794)
			(stroke
				(width 0.1)
				(type default)
			)
			(layer "F.Fab")
		)
		(fp_line
			(start 0.67945 0.3048)
			(end 0.120396 0.3048)
			(stroke
				(width 0.1)
				(type default)
			)
			(layer "F.Fab")
		)
		(fp_line
			(start -0.12065 0.2794)
			(end -0.12065 0.3048)
			(stroke
				(width 0.1)
				(type default)
			)
			(layer "F.Fab")
		)
		(fp_line
			(start 0.120396 0.2794)
			(end -0.12065 0.2794)
			(stroke
				(width 0.1)
				(type default)
			)
			(layer "F.Fab")
		)
		(fp_line
			(start -0.12065 -0.2794)
			(end 0.12065 -0.2794)
			(stroke
				(width 0.1)
				(type default)
			)
			(layer "F.Fab")
		)
		(fp_line
			(start 0.12065 -0.2794)
			(end 0.12065 -0.3048)
			(stroke
				(width 0.1)
				(type default)
			)
			(layer "F.Fab")
		)
		(fp_line
			(start 0.12065 -0.3048)
			(end 0.67945 -0.3048)
			(stroke
				(width 0.1)
				(type default)
			)
			(layer "F.Fab")
		)
		(fp_line
			(start 0.67945 -0.3048)
			(end 0.67945 0.3048)
			(stroke
				(width 0.1)
				(type default)
			)
			(layer "F.Fab")
		)
		(fp_line
			(start -0.67945 -0.305054)
			(end -0.12065 -0.305054)
			(stroke
				(width 0.1)
				(type default)
			)
			(layer "F.Fab")
		)
		(fp_line
			(start -0.12065 -0.305054)
			(end -0.12065 -0.2794)
			(stroke
				(width 0.1)
				(type default)
			)
			(layer "F.Fab")
		)
		(pad "1" smd circle
			(at -0.40005 0 270)
			(size 0 0)
			(layers "F.Cu" "F.Mask" "F.Paste")
			(net "PWRGD_P5V_AUX")
		)
		(pad "2" smd circle
			(at 0.40005 0 270)
			(size 0 0)
			(layers "F.Cu" "F.Mask" "F.Paste")
			(net "GND")
		)
	)
)
